(kicad_pcb
	(version 20260206)
	(generator "pcbnew")
	(generator_version "10.0")
	(general
		(thickness 1.6)
		(legacy_teardrops no)
	)
	(paper "A4")
	(title_block
		(title "dpb — 14545-sa.0730WZS0815.brd")
		(comment 1 "Honey Badger (Wiwynn) / footprints 1014-1021 of 1066")
	)
	(layers
		(0 "F.Cu" signal "TOP")
		(4 "In1.Cu" signal "L2GND")
		(6 "In2.Cu" signal "L3")
		(8 "In3.Cu" signal "L4VCC")
		(10 "In4.Cu" signal "L5VCC")
		(12 "In5.Cu" signal "L6")
		(14 "In6.Cu" signal "L7GND")
		(2 "B.Cu" signal "BOTTOM")
		(9 "F.Adhes" user "F.Adhesive")
		(11 "B.Adhes" user "B.Adhesive")
		(13 "F.Paste" user "Package Geometry/Pastemask Top")
		(15 "B.Paste" user "Package Geometry/Pastemask Bottom")
		(5 "F.SilkS" user "Ref Des/Silkscreen Top")
		(7 "B.SilkS" user "Ref Des/Silkscreen Bottom")
		(1 "F.Mask" user "Board Geometry/Soldermask Top")
		(3 "B.Mask" user "Board Geometry/Soldermask Bottom")
		(17 "Dwgs.User" user "User.Drawings")
		(19 "Cmts.User" user "User.Comments")
		(21 "Eco1.User" user "User.Eco1")
		(23 "Eco2.User" user "User.Eco2")
		(25 "Edge.Cuts" user "Board Geometry/Outline")
		(27 "Margin" user)
		(31 "F.CrtYd" user "Package Geometry/Place Bound Top")
		(29 "B.CrtYd" user "Package Geometry/Place Bound Bottom")
		(35 "F.Fab" user "Ref Des/Assembly Top")
		(33 "B.Fab" user "Ref Des/Assembly Bottom")
	)
	(footprint ""
		(layer "F.Cu")
		(at 52.197 -420.497 90)
		(property "Reference" "D25"
			(at 0 0 90)
			(layer "F.SilkS")
			(hide yes)
			(effects
				(font
					(size 1.27 1.27)
				)
			)
		)
		(property "Value" "RB551V30-1-GP"
			(at 0 -6.7818 90)
			(unlocked yes)
			(layer "F.Fab")
			(hide yes)
			(effects
				(font
					(size 1.016 1.016)
					(thickness 0.1524)
				)
			)
		)
		(property "Device Type" "SOD323AKH44"
			(at 0 -8.6868 90)
			(unlocked yes)
			(layer "F.Fab")
			(hide yes)
			(effects
				(font
					(size 1.016 1.016)
					(thickness 0.1524)
				)
			)
		)
		(duplicate_pad_numbers_are_jumpers no)
		(fp_line
			(start 0.889 -1.9304)
			(end 0.889 2.159)
			(stroke
				(width 0.1524)
				(type default)
			)
			(layer "F.SilkS")
		)
		(fp_line
			(start -0.889 -1.9304)
			(end 0.889 -1.9304)
			(stroke
				(width 0.1524)
				(type default)
			)
			(layer "F.SilkS")
		)
		(fp_line
			(start 0.762 2.0574)
			(end -0.762 2.0574)
			(stroke
				(width 0.508)
				(type default)
			)
			(layer "F.SilkS")
		)
		(fp_line
			(start 0.889 2.159)
			(end -0.889 2.159)
			(stroke
				(width 0.1524)
				(type default)
			)
			(layer "F.SilkS")
		)
		(fp_line
			(start -0.889 2.159)
			(end -0.889 -1.9304)
			(stroke
				(width 0.1524)
				(type default)
			)
			(layer "F.SilkS")
		)
		(fp_rect
			(start -1.016 2.3114)
			(end 1.016 -2.0066)
			(stroke
				(width 0)
				(type default)
			)
			(fill no)
			(layer "F.CrtYd")
		)
		(fp_poly
			(pts
				(xy -1.016 -2.0066) (xy 1.016 -2.0066) (xy 1.016 2.3114) (xy -1.016 2.3114)
			)
			(stroke
				(width 0)
				(type default)
			)
			(fill no)
			(layer "F.Fab")
		)
		(pad "A" smd rect
			(at 0 -1.143 90)
			(size 0.5588 1.016)
			(layers "F.Cu" "F.Mask" "F.Paste")
			(net "SW_HDD10_R")
		)
		(pad "K" smd rect
			(at 0 1.143 90)
			(size 0.5588 1.016)
			(layers "F.Cu" "F.Mask" "F.Paste")
			(net "SW_HDD10_N")
		)
	)
	(footprint ""
		(layer "F.Cu")
		(at 54.228746 -25.2857)
		(property "Reference" "PC19"
			(at 0 0 0)
			(layer "F.SilkS")
			(hide yes)
			(effects
				(font
					(size 1.27 1.27)
				)
			)
		)
		(property "Value" "SC680P50V2KX-2GP"
			(at 1.1811 -2.7051 0)
			(unlocked yes)
			(layer "F.Fab")
			(hide yes)
			(effects
				(font
					(size 1.016 1.016)
					(thickness 0.1524)
				)
			)
		)
		(property "Device Type" "C402H22"
			(at 1.1811 -4.2291 0)
			(unlocked yes)
			(layer "F.Fab")
			(hide yes)
			(effects
				(font
					(size 1.016 1.016)
					(thickness 0.1524)
				)
			)
		)
		(duplicate_pad_numbers_are_jumpers no)
		(fp_rect
			(start -0.4318 0.9525)
			(end 0.4318 -0.9525)
			(stroke
				(width 0)
				(type default)
			)
			(fill no)
			(layer "F.CrtYd")
		)
		(fp_rect
			(start -0.4318 0.9525)
			(end 0.4318 -0.9525)
			(stroke
				(width 0)
				(type default)
			)
			(fill no)
			(layer "F.Fab")
		)
		(pad "1" smd custom
			(at 0 -0.4445)
			(size 0.1524 0.1524)
			(layers "F.Cu" "F.Mask" "F.Paste")
			(net "P5VB_LL_NET")
			(options
				(clearance outline)
				(anchor circle)
			)
			(primitives
				(gr_poly
					(pts
						(arc
							(start 0.3048 -0.2032)
							(mid 0.275042 -0.275042)
							(end 0.2032 -0.3048)
						)
						(arc
							(start -0.2032 -0.3048)
							(mid -0.275042 -0.275042)
							(end -0.3048 -0.2032)
						)
						(arc
							(start -0.3048 0.2032)
							(mid -0.275042 0.275042)
							(end -0.2032 0.3048)
						)
						(arc
							(start 0.2032 0.3048)
							(mid 0.275042 0.275042)
							(end 0.3048 0.2032)
						)
					)
					(width 0)
					(fill yes)
				)
			)
		)
		(pad "2" smd custom
			(at 0 0.4445)
			(size 0.1524 0.1524)
			(layers "F.Cu" "F.Mask" "F.Paste")
			(net "P5VB_VFB")
			(options
				(clearance outline)
				(anchor circle)
			)
			(primitives
				(gr_poly
					(pts
						(arc
							(start 0.3048 -0.2032)
							(mid 0.275042 -0.275042)
							(end 0.2032 -0.3048)
						)
						(arc
							(start -0.2032 -0.3048)
							(mid -0.275042 -0.275042)
							(end -0.3048 -0.2032)
						)
						(arc
							(start -0.3048 0.2032)
							(mid -0.275042 0.275042)
							(end -0.2032 0.3048)
						)
						(arc
							(start 0.2032 0.3048)
							(mid 0.275042 0.275042)
							(end 0.3048 0.2032)
						)
					)
					(width 0)
					(fill yes)
				)
			)
		)
	)
	(footprint ""
		(layer "F.Cu")
		(at 206.469742 -76.192634 90)
		(property "Reference" "Q9"
			(at 0 0 90)
			(layer "F.SilkS")
			(hide yes)
			(effects
				(font
					(size 1.27 1.27)
				)
			)
		)
		(property "Value" "AO4406AL-GP"
			(at -3.707384 -1.5367 90)
			(unlocked yes)
			(layer "F.Fab")
			(hide yes)
			(effects
				(font
					(size 1.016 1.016)
					(thickness 0.1524)
				)
			)
		)
		(property "Device Type" "SOIC8H69"
			(at -3.707384 -3.0607 90)
			(unlocked yes)
			(layer "F.Fab")
			(hide yes)
			(effects
				(font
					(size 1.016 1.016)
					(thickness 0.1524)
				)
			)
		)
		(duplicate_pad_numbers_are_jumpers no)
		(fp_line
			(start 2.1336 -1.4224)
			(end -2.7432 -1.4224)
			(stroke
				(width 0.1524)
				(type default)
			)
			(layer "F.SilkS")
		)
		(fp_line
			(start -2.7432 -1.4224)
			(end -2.7432 1.4224)
			(stroke
				(width 0.1524)
				(type default)
			)
			(layer "F.SilkS")
		)
		(fp_line
			(start -2.7178 -0.508)
			(end -2.1844 -0.0508)
			(stroke
				(width 0.1524)
				(type default)
			)
			(layer "F.SilkS")
		)
		(fp_line
			(start -2.1844 -0.0508)
			(end -2.7178 0.508)
			(stroke
				(width 0.1524)
				(type default)
			)
			(layer "F.SilkS")
		)
		(fp_line
			(start 2.1336 1.4224)
			(end 2.1336 -1.4224)
			(stroke
				(width 0.1524)
				(type default)
			)
			(layer "F.SilkS")
		)
		(fp_line
			(start -2.7432 1.4224)
			(end 2.1336 1.4224)
			(stroke
				(width 0.1524)
				(type default)
			)
			(layer "F.SilkS")
		)
		(fp_line
			(start -2.7432 1.4224)
			(end -2.6416 1.4224)
			(stroke
				(width 0.1524)
				(type default)
			)
			(layer "F.SilkS")
		)
		(fp_line
			(start -2.6289 3.4417)
			(end -2.6289 1.4732)
			(stroke
				(width 0.381)
				(type default)
			)
			(layer "F.SilkS")
		)
		(fp_poly
			(pts
				(xy -2.2098 -1.4224) (xy -2.2098 1.4224) (xy 2.2098 1.4224) (xy 2.2098 -1.4224)
			)
			(stroke
				(width 0)
				(type default)
			)
			(fill yes)
			(layer "F.SilkS")
		)
		(fp_rect
			(start -2.450084 2.999994)
			(end 2.450084 -2.999994)
			(stroke
				(width 0)
				(type default)
			)
			(fill no)
			(layer "F.CrtYd")
		)
		(fp_poly
			(pts
				(xy -2.8194 3.6322) (xy -2.8194 -3.6322) (xy 2.8194 -3.6322) (xy 2.8194 1.18364) (xy 2.450084 1.18364)
				(xy 2.450084 -2.999994) (xy -2.450084 -2.999994) (xy -2.450084 2.999994) (xy 2.450084 2.999994)
				(xy 2.450084 1.18618) (xy 2.8194 1.18618) (xy 2.8194 3.6322)
			)
			(stroke
				(width 0)
				(type default)
			)
			(fill no)
			(layer "F.CrtYd")
		)
		(fp_rect
			(start -2.8194 3.6322)
			(end 2.8194 -3.6322)
			(stroke
				(width 0)
				(type default)
			)
			(fill no)
			(layer "F.Fab")
		)
		(pad "1" smd rect
			(at -1.905 2.54 90)
			(size 0.635 1.651)
			(layers "F.Cu" "F.Mask" "F.Paste")
			(net "P5V_HDD4")
		)
		(pad "2" smd rect
			(at -0.635 2.54 90)
			(size 0.635 1.651)
			(layers "F.Cu" "F.Mask" "F.Paste")
			(net "P5V_HDD4")
		)
		(pad "3" smd rect
			(at 0.635 2.54 90)
			(size 0.635 1.651)
			(layers "F.Cu" "F.Mask" "F.Paste")
			(net "P5V_HDD4")
		)
		(pad "4" smd rect
			(at 1.905 2.54 90)
			(size 0.635 1.651)
			(layers "F.Cu" "F.Mask" "F.Paste")
			(net "SW_HDD4_P")
		)
		(pad "5" smd rect
			(at 1.905 -2.54 90)
			(size 0.635 1.651)
			(layers "F.Cu" "F.Mask" "F.Paste")
			(net "P5VA")
		)
		(pad "6" smd rect
			(at 0.635 -2.54 90)
			(size 0.635 1.651)
			(layers "F.Cu" "F.Mask" "F.Paste")
			(net "P5VA")
		)
		(pad "7" smd rect
			(at -0.635 -2.54 90)
			(size 0.635 1.651)
			(layers "F.Cu" "F.Mask" "F.Paste")
			(net "P5VA")
		)
		(pad "8" smd rect
			(at -1.905 -2.54 90)
			(size 0.635 1.651)
			(layers "F.Cu" "F.Mask" "F.Paste")
			(net "P5VA")
		)
	)
	(footprint ""
		(layer "F.Cu")
		(at 68.999608 -376.999754)
		(property "Reference" "H3"
			(at 0 0 0)
			(layer "F.SilkS")
			(hide yes)
			(effects
				(font
					(size 1.27 1.27)
				)
			)
		)
		(property "Value" "HOLE315R140"
			(at 0 -7.5692 0)
			(unlocked yes)
			(layer "F.Fab")
			(hide yes)
			(effects
				(font
					(size 1.016 1.016)
					(thickness 0.1524)
				)
			)
		)
		(property "Device Type" "HOLE315R140"
			(at 0 -9.0932 0)
			(unlocked yes)
			(layer "F.Fab")
			(hide yes)
			(effects
				(font
					(size 1.016 1.016)
					(thickness 0.1524)
				)
			)
		)
		(duplicate_pad_numbers_are_jumpers no)
		(fp_poly
			(pts
				(arc
					(start 4.3053 0)
					(mid -4.3053 0)
					(end 4.3053 0)
				)
			)
			(stroke
				(width 0)
				(type default)
			)
			(fill no)
			(layer "F.CrtYd")
		)
		(fp_poly
			(pts
				(arc
					(start 4.3053 0)
					(mid -4.3053 0)
					(end 4.3053 0)
				)
			)
			(stroke
				(width 0)
				(type default)
			)
			(fill no)
			(layer "F.Fab")
		)
		(pad "1" thru_hole circle
			(at 0.00127 0.00127)
			(size 8.001 8.001)
			(drill 3.556)
			(layers "*.Cu" "*.Mask")
			(remove_unused_layers no)
			(net "GND")
			(clearance -1.7145)
			(thermal_gap 0.3048)
			(padstack
				(mode front_inner_back)
				(layer "Inner"
					(shape circle)
					(size 3.9624 3.9624)
					(clearance 0.3048)
				)
				(layer "B.Cu"
					(shape circle)
					(size 8.001 8.001)
					(clearance -1.7145)
				)
			)
		)
	)
	(footprint ""
		(layer "F.Cu")
		(at 214.8332 -275.1328 -90)
		(property "Reference" "R365"
			(at 0 0 270)
			(layer "F.SilkS")
			(hide yes)
			(effects
				(font
					(size 1.27 1.27)
				)
			)
		)
		(property "Value" "0R2J-2-GP"
			(at 0.064008 -3.993896 270)
			(unlocked yes)
			(layer "F.Fab")
			(hide yes)
			(effects
				(font
					(size 1.016 1.016)
					(thickness 0.1524)
				)
			)
		)
		(property "Device Type" "R402H16"
			(at 0.064008 -5.517896 270)
			(unlocked yes)
			(layer "F.Fab")
			(hide yes)
			(effects
				(font
					(size 1.016 1.016)
					(thickness 0.1524)
				)
			)
		)
		(duplicate_pad_numbers_are_jumpers no)
		(fp_line
			(start -0.508 -0.9398)
			(end -0.508 0.9398)
			(stroke
				(width 0.1524)
				(type default)
			)
			(layer "F.SilkS")
		)
		(fp_line
			(start 0.508 -0.9398)
			(end -0.508 -0.9398)
			(stroke
				(width 0.1524)
				(type default)
			)
			(layer "F.SilkS")
		)
		(fp_rect
			(start -0.508 0.9398)
			(end 0.508 -0.9398)
			(stroke
				(width 0)
				(type default)
			)
			(fill no)
			(layer "F.CrtYd")
		)
		(fp_rect
			(start -0.508 0.9398)
			(end 0.508 -0.9398)
			(stroke
				(width 0)
				(type default)
			)
			(fill no)
			(layer "F.Fab")
		)
		(pad "1" smd custom
			(at 0 -0.4445 270)
			(size 0.1397 0.1397)
			(layers "F.Cu" "F.Mask" "F.Paste")
			(net "HDD_PRSNT_NET2")
			(options
				(clearance outline)
				(anchor circle)
			)
			(primitives
				(gr_poly
					(pts
						(arc
							(start -0.1778 -0.2794)
							(mid -0.249642 -0.249642)
							(end -0.2794 -0.1778)
						)
						(arc
							(start -0.2794 0.1778)
							(mid -0.249642 0.249642)
							(end -0.1778 0.2794)
						)
						(arc
							(start 0.1778 0.2794)
							(mid 0.249642 0.249642)
							(end 0.2794 0.1778)
						)
						(arc
							(start 0.2794 -0.1778)
							(mid 0.249642 -0.249642)
							(end 0.1778 -0.2794)
						)
					)
					(width 0)
					(fill yes)
				)
			)
		)
		(pad "2" smd custom
			(at 0 0.4445 270)
			(size 0.1397 0.1397)
			(layers "F.Cu" "F.Mask" "F.Paste")
			(net "HDD2_LED_B")
			(options
				(clearance outline)
				(anchor circle)
			)
			(primitives
				(gr_poly
					(pts
						(arc
							(start -0.1778 -0.2794)
							(mid -0.249642 -0.249642)
							(end -0.2794 -0.1778)
						)
						(arc
							(start -0.2794 0.1778)
							(mid -0.249642 0.249642)
							(end -0.1778 0.2794)
						)
						(arc
							(start 0.1778 0.2794)
							(mid 0.249642 0.249642)
							(end 0.2794 0.1778)
						)
						(arc
							(start 0.2794 -0.1778)
							(mid 0.249642 -0.249642)
							(end 0.1778 -0.2794)
						)
					)
					(width 0)
					(fill yes)
				)
			)
		)
	)
	(footprint ""
		(layer "F.Cu")
		(at 26.415746 -314.4647)
		(property "Reference" "C291"
			(at 0 0 0)
			(layer "F.SilkS")
			(hide yes)
			(effects
				(font
					(size 1.27 1.27)
				)
			)
		)
		(property "Value" "SC1U25V3KX-1-GP"
			(at 0 -2.8194 0)
			(unlocked yes)
			(layer "F.Fab")
			(hide yes)
			(effects
				(font
					(size 1.016 1.016)
					(thickness 0.1524)
				)
			)
		)
		(property "Device Type" "C603H36"
			(at 0 -4.3434 0)
			(unlocked yes)
			(layer "F.Fab")
			(hide yes)
			(effects
				(font
					(size 1.016 1.016)
					(thickness 0.1524)
				)
			)
		)
		(duplicate_pad_numbers_are_jumpers no)
		(fp_line
			(start 0.508 0)
			(end -0.508 0)
			(stroke
				(width 0.2032)
				(type default)
			)
			(layer "F.SilkS")
		)
		(fp_rect
			(start -0.5842 1.3335)
			(end 0.5842 -1.3335)
			(stroke
				(width 0)
				(type default)
			)
			(fill no)
			(layer "F.CrtYd")
		)
		(fp_rect
			(start -0.5842 1.3335)
			(end 0.5842 -1.3335)
			(stroke
				(width 0)
				(type default)
			)
			(fill no)
			(layer "F.Fab")
		)
		(pad "1" smd custom
			(at 0 -0.762)
			(size 0.2159 0.2159)
			(layers "F.Cu" "F.Mask" "F.Paste")
			(net "P12V_HDD11")
			(options
				(clearance outline)
				(anchor circle)
			)
			(primitives
				(gr_poly
					(pts
						(arc
							(start -0.3302 -0.4318)
							(mid -0.402042 -0.402042)
							(end -0.4318 -0.3302)
						)
						(arc
							(start -0.4318 0.3302)
							(mid -0.402042 0.402042)
							(end -0.3302 0.4318)
						)
						(arc
							(start 0.3302 0.4318)
							(mid 0.402042 0.402042)
							(end 0.4318 0.3302)
						)
						(arc
							(start 0.4318 -0.3302)
							(mid 0.402042 -0.402042)
							(end 0.3302 -0.4318)
						)
					)
					(width 0)
					(fill yes)
				)
			)
		)
		(pad "2" smd custom
			(at 0 0.762)
			(size 0.2159 0.2159)
			(layers "F.Cu" "F.Mask" "F.Paste")
			(net "GND")
			(options
				(clearance outline)
				(anchor circle)
			)
			(primitives
				(gr_poly
					(pts
						(arc
							(start -0.3302 -0.4318)
							(mid -0.402042 -0.402042)
							(end -0.4318 -0.3302)
						)
						(arc
							(start -0.4318 0.3302)
							(mid -0.402042 0.402042)
							(end -0.3302 0.4318)
						)
						(arc
							(start 0.3302 0.4318)
							(mid 0.402042 0.402042)
							(end 0.4318 0.3302)
						)
						(arc
							(start 0.4318 -0.3302)
							(mid 0.402042 -0.402042)
							(end 0.3302 -0.4318)
						)
					)
					(width 0)
					(fill yes)
				)
			)
		)
	)
	(footprint ""
		(layer "F.Cu")
		(at 54.8386 -228.2698 180)
		(property "Reference" "C293"
			(at 0 0 180)
			(layer "F.SilkS")
			(hide yes)
			(effects
				(font
					(size 1.27 1.27)
				)
			)
		)
		(property "Value" "SCD1U10V2KX-5GP"
			(at 1.1811 -2.7051 180)
			(unlocked yes)
			(layer "F.Fab")
			(hide yes)
			(effects
				(font
					(size 1.016 1.016)
					(thickness 0.1524)
				)
			)
		)
		(property "Device Type" "C402H22"
			(at 1.1811 -4.2291 180)
			(unlocked yes)
			(layer "F.Fab")
			(hide yes)
			(effects
				(font
					(size 1.016 1.016)
					(thickness 0.1524)
				)
			)
		)
		(duplicate_pad_numbers_are_jumpers no)
		(fp_rect
			(start -0.4318 0.9525)
			(end 0.4318 -0.9525)
			(stroke
				(width 0)
				(type default)
			)
			(fill no)
			(layer "F.CrtYd")
		)
		(fp_rect
			(start -0.4318 0.9525)
			(end 0.4318 -0.9525)
			(stroke
				(width 0)
				(type default)
			)
			(fill no)
			(layer "F.Fab")
		)
		(pad "1" smd custom
			(at 0 -0.4445 180)
			(size 0.1524 0.1524)
			(layers "F.Cu" "F.Mask" "F.Paste")
			(net "P3V3")
			(options
				(clearance outline)
				(anchor circle)
			)
			(primitives
				(gr_poly
					(pts
						(arc
							(start 0.3048 -0.2032)
							(mid 0.275042 -0.275042)
							(end 0.2032 -0.3048)
						)
						(arc
							(start -0.2032 -0.3048)
							(mid -0.275042 -0.275042)
							(end -0.3048 -0.2032)
						)
						(arc
							(start -0.3048 0.2032)
							(mid -0.275042 0.275042)
							(end -0.2032 0.3048)
						)
						(arc
							(start 0.2032 0.3048)
							(mid 0.275042 0.275042)
							(end 0.3048 0.2032)
						)
					)
					(width 0)
					(fill yes)
				)
			)
		)
		(pad "2" smd custom
			(at 0 0.4445 180)
			(size 0.1524 0.1524)
			(layers "F.Cu" "F.Mask" "F.Paste")
			(net "GND")
			(options
				(clearance outline)
				(anchor circle)
			)
			(primitives
				(gr_poly
					(pts
						(arc
							(start 0.3048 -0.2032)
							(mid 0.275042 -0.275042)
							(end 0.2032 -0.3048)
						)
						(arc
							(start -0.2032 -0.3048)
							(mid -0.275042 -0.275042)
							(end -0.3048 -0.2032)
						)
						(arc
							(start -0.3048 0.2032)
							(mid -0.275042 0.275042)
							(end -0.2032 0.3048)
						)
						(arc
							(start 0.2032 0.3048)
							(mid 0.275042 0.275042)
							(end 0.3048 0.2032)
						)
					)
					(width 0)
					(fill yes)
				)
			)
		)
	)
	(footprint ""
		(layer "F.Cu")
		(at 33.2613 -273.7104 90)
		(property "Reference" "C36"
			(at 0 0 90)
			(layer "F.SilkS")
			(hide yes)
			(effects
				(font
					(size 1.27 1.27)
				)
			)
		)
		(property "Value" "SCD01U50V2KX-1GP"
			(at 1.1811 -2.7051 90)
			(unlocked yes)
			(layer "F.Fab")
			(hide yes)
			(effects
				(font
					(size 1.016 1.016)
					(thickness 0.1524)
				)
			)
		)
		(property "Device Type" "C402H22"
			(at 1.1811 -4.2291 90)
			(unlocked yes)
			(layer "F.Fab")
			(hide yes)
			(effects
				(font
					(size 1.016 1.016)
					(thickness 0.1524)
				)
			)
		)
		(duplicate_pad_numbers_are_jumpers no)
		(fp_rect
			(start -0.4318 0.9525)
			(end 0.4318 -0.9525)
			(stroke
				(width 0)
				(type default)
			)
			(fill no)
			(layer "F.CrtYd")
		)
		(fp_rect
			(start -0.4318 0.9525)
			(end 0.4318 -0.9525)
			(stroke
				(width 0)
				(type default)
			)
			(fill no)
			(layer "F.Fab")
		)
		(pad "1" smd custom
			(at 0 -0.4445 90)
			(size 0.1524 0.1524)
			(layers "F.Cu" "F.Mask" "F.Paste")
			(net "SEB_BA_TX+")
			(options
				(clearance outline)
				(anchor circle)
			)
			(primitives
				(gr_poly
					(pts
						(arc
							(start 0.3048 -0.2032)
							(mid 0.275042 -0.275042)
							(end 0.2032 -0.3048)
						)
						(arc
							(start -0.2032 -0.3048)
							(mid -0.275042 -0.275042)
							(end -0.3048 -0.2032)
						)
						(arc
							(start -0.3048 0.2032)
							(mid -0.275042 0.275042)
							(end -0.2032 0.3048)
						)
						(arc
							(start 0.2032 0.3048)
							(mid 0.275042 0.275042)
							(end 0.3048 0.2032)
						)
					)
					(width 0)
					(fill yes)
				)
			)
		)
		(pad "2" smd custom
			(at 0 0.4445 90)
			(size 0.1524 0.1524)
			(layers "F.Cu" "F.Mask" "F.Paste")
			(net "SEB_BA_RX+")
			(options
				(clearance outline)
				(anchor circle)
			)
			(primitives
				(gr_poly
					(pts
						(arc
							(start 0.3048 -0.2032)
							(mid 0.275042 -0.275042)
							(end 0.2032 -0.3048)
						)
						(arc
							(start -0.2032 -0.3048)
							(mid -0.275042 -0.275042)
							(end -0.3048 -0.2032)
						)
						(arc
							(start -0.3048 0.2032)
							(mid -0.275042 0.275042)
							(end -0.2032 0.3048)
						)
						(arc
							(start 0.2032 0.3048)
							(mid 0.275042 0.275042)
							(end 0.3048 0.2032)
						)
					)
					(width 0)
					(fill yes)
				)
			)
		)
	)
)
